%FSTAX25Y25*%
%MOIN*%
%SFA1B1*%

%IPPOS*%
%ADD77R,1.354330X0.230320*%
%ADD78R,0.314960X0.135830*%
%ADD106R,0.036000X0.173000*%
%ADD107R,0.036000X0.134000*%
%ADD117R,0.065090X0.053280*%
%ADD119R,0.033200X0.034770*%
%ADD124R,0.053280X0.065090*%
%ADD125R,0.034770X0.033200*%
%ADD129R,0.090870X0.052090*%
%ADD130C,0.258000*%
%ADD131C,0.039500*%
%ADD132C,0.073980*%
%ADD133C,0.008000*%
%ADD134C,0.083000*%
%ADD135C,0.106420*%
%ADD136O,0.204850X0.106420*%
%ADD137O,0.185170X0.096580*%
%ADD138O,0.096580X0.185170*%
%ADD139C,0.128000*%
%ADD140C,0.120000*%
%ADD141C,0.029660*%
%ADD142R,0.008000X0.008000*%
%ADD143C,0.063000*%
%ADD144R,0.063000X0.063000*%
%ADD145C,0.058000*%
%ADD146C,0.024000*%
%LNgrandmaster-1*%
%LPD*%
G54D77*
X0843701Y0511516D03*
G54D78*
X074602Y0524997D03*
G54D106*
X0908661Y0514173D03*
X0786614D03*
X0782677D03*
X0814173D03*
X0810236D03*
X0869291D03*
X0900787D03*
X089685D03*
X0885039D03*
X0865354D03*
X0881102D03*
X0849606D03*
X0845669D03*
X0837795D03*
X0833858D03*
X081811D03*
X0794488D03*
X0798425D03*
X0802362D03*
X0806299D03*
X085748D03*
X0841732D03*
X0829921D03*
X0877165D03*
X0892913D03*
X0873228D03*
X0904724D03*
X0888976D03*
X0861417D03*
X0853543D03*
X0790551D03*
G54D107*
X077874Y0516123D03*
G54D117*
X08623Y0804643D03*
Y0797557D03*
G54D119*
X0834Y0536693D03*
Y0533307D03*
X0838D03*
Y0536693D03*
X08459D03*
Y0533307D03*
X08502D03*
Y0536693D03*
X08655Y0533307D03*
Y0536693D03*
X08695Y0533307D03*
Y0536693D03*
X0881Y0533307D03*
Y0536693D03*
X08845D03*
Y0533307D03*
X0897D03*
Y0536693D03*
X0901Y0533307D03*
Y0536693D03*
X08702Y0804093D03*
Y0800707D03*
G54D124*
X0831757Y07948D03*
X0838843D03*
G54D125*
X0834207Y07858D03*
X0837593D03*
G54D129*
X085Y0804678D03*
Y0820426D03*
Y0812552D03*
Y08283D03*
X08325Y0804678D03*
Y0812552D03*
Y0820426D03*
Y08283D03*
G54D130*
X06285Y05373D03*
X13206Y05701D03*
X06294Y09156D03*
X13206Y09168D03*
G54D131*
X09775Y0913D03*
X0994823D03*
G54D132*
X08985Y0909004D03*
X09285D03*
G54D133*
X084125Y0824363D03*
Y0808615D03*
X084075Y0844937D03*
Y0860685D03*
G54D134*
X1028878Y0759928D03*
X1017067D03*
X1005256D03*
X0996988Y0589456D03*
Y0749298D03*
X1156831D03*
Y0669377D03*
Y0589456D03*
G54D135*
X117122Y0896D03*
Y091411D03*
X1255965Y0881D03*
Y0859346D03*
X12725Y0881D03*
Y0859346D03*
X1289035D03*
Y0881D03*
G54D136*
X1211Y0882378D03*
G54D137*
X1211Y0906D03*
G54D138*
X1192496Y0894189D03*
G54D139*
X0609Y0601D03*
Y0581D03*
X0629D03*
Y0601D03*
X0609Y07585D03*
Y07385D03*
X0629D03*
Y07585D03*
X0609Y0706D03*
Y0686D03*
X0629D03*
Y0706D03*
X0609Y06535D03*
Y06335D03*
X0629D03*
Y06535D03*
G54D140*
X0619Y0591D03*
Y07485D03*
Y0696D03*
Y06435D03*
G54D141*
X0898069Y0744247D03*
X089807Y0596253D03*
X081933D03*
X0768699Y0710117D03*
Y0631377D03*
X0819329Y0744247D03*
X095619Y0631373D03*
Y0710113D03*
G54D142*
X096081Y0592023D03*
X076421Y0749023D03*
X076431Y0592023D03*
X096081Y0749023D03*
G54D143*
X0803Y09156D03*
Y09056D03*
X07429Y09164D03*
Y09064D03*
G54D144*
X0803Y09256D03*
X07429Y09264D03*
G54D145*
X1255965Y090974D03*
X1289035D03*
G54D146*
X090876Y0524705D03*
X0894587Y0525591D03*
X0853622Y0524878D03*
X0843701Y0525D03*
X08422Y05285D03*
X08398D03*
X0806693Y0525984D03*
Y0529134D03*
X0810236D03*
X0814173D03*
X0810236Y0525984D03*
X0814173D03*
X079063Y052487D03*
X0782283Y0525984D03*
X0784252D03*
X0786221D03*
X0782283Y0529134D03*
X0784252D03*
X0786221D03*
X0876Y0529D03*
X08736D03*
X08898Y05287D03*
X08025Y0525D03*
X08595Y05288D03*
X0862703Y0525184D03*
X0788746Y0652046D03*
X0878937Y0525591D03*
X083Y0525D03*
X08566Y05289D03*
X08922Y05287D03*
X0887205Y0525689D03*
X07788Y05359D03*
X0891732Y0814961D03*
X0885827D03*
X0883071D03*
X0888976D03*
X0891732Y0811811D03*
X0885827D03*
X0883071D03*
X0888976D03*
X0891732Y081811D03*
X0885827D03*
X0883071D03*
X0888976D03*
Y082126D03*
X0883071D03*
X0885827D03*
X0891732D03*
X1224409Y0791339D03*
X126378Y0813386D03*
X1125716Y0909284D03*
X1033Y07729D03*
X1049382Y0779382D03*
X082219Y075881D03*
X082425Y076175D03*
X0826219Y0746781D03*
X09562Y07062D03*
X0931933Y0683D03*
X0940462Y06809D03*
X0942941Y0687488D03*
X0996Y06556D03*
X0781294Y0667794D03*
X0787009Y0681574D03*
X0755836Y0707164D03*
X11985Y08556D03*
X09592Y08142D03*
Y07896D03*
X08975Y0805D03*
X0907Y07985D03*
X1004Y08669D03*
X0982Y0881D03*
X07779Y09331D03*
X09581Y06666D03*
X08321Y07219D03*
X11568Y07218D03*
X08774Y07572D03*
X07712Y06993D03*
X08693Y07293D03*
X08685Y06485D03*
X10055Y06515D03*
X08887Y08382D03*
X0838Y08485D03*
X08375Y06945D03*
X09795Y06844D03*
X08505Y05941D03*
X08656Y06096D03*
X09821Y08766D03*
X12325Y0827D03*
X09735Y08265D03*
X0976402Y0667004D03*
X08314Y0759D03*
X07662Y06796D03*
X08774Y06098D03*
X09386Y09226D03*
X10263Y08139D03*
X0971Y07D03*
X09401Y0671759D03*
X0849Y0724D03*
X11625D03*
X08615Y07465D03*
X08617Y06774D03*
X10055Y068D03*
X07705Y06599D03*
X1085Y08D03*
X12295Y08125D03*
X0993D03*
X09915Y0654D03*
X08716Y08164D03*
X08717Y08329D03*
X09048Y08159D03*
X0813Y08742D03*
X0918742Y06718D03*
X09188Y07974D03*
X08414Y08127D03*
X08479Y07417D03*
X08401Y06093D03*
X1012Y0852D03*
X08485Y07665D03*
X0903536Y0821364D03*
X10199Y08139D03*
X09585Y06518D03*
X08676Y07572D03*
X07662Y06403D03*
X08137Y07757D03*
X10125Y06755D03*
X08595Y06738D03*
X0859Y0744D03*
X12617Y08036D03*
X10143Y08139D03*
X08694Y05952D03*
X08245Y0854D03*
X0829Y0692D03*
X09545Y06895D03*
X10055Y07726D03*
X08485Y077D03*
X08715Y08525D03*
X08302Y05938D03*
X08862Y07301D03*
X07666Y06895D03*
X08845Y05399D03*
X0881D03*
X0888285Y0583251D03*
X08852Y05824D03*
X07239Y07004D03*
X0971Y06925D03*
X09404Y06577D03*
X0857Y07285D03*
Y06794D03*
X09935Y0682D03*
X07712Y06698D03*
X08807Y07907D03*
X08907D03*
X10122Y0669D03*
X08303Y06097D03*
X10059Y08139D03*
X08665Y08505D03*
X10225Y07729D03*
X08714Y07924D03*
X08395Y07416D03*
X09723Y06422D03*
X08577Y07573D03*
X07662Y06501D03*
X09545Y06995D03*
X08961Y08415D03*
X12447Y08013D03*
X07682Y09083D03*
X09633Y0564D03*
X0825Y08265D03*
X09365Y08277D03*
X09359Y08054D03*
X08774Y07433D03*
X07665Y06993D03*
X1003Y08788D03*
X12467Y08235D03*
X10324Y08139D03*
X10468D03*
X09545Y06845D03*
X09397Y06465D03*
X08566Y07416D03*
X1003Y0741D03*
X07707Y06403D03*
X07709Y06796D03*
X07548Y09233D03*
X09188Y08218D03*
X07717Y0933D03*
X08244Y07283D03*
X08924Y05957D03*
X0971Y0677D03*
X0854Y06759D03*
X08625Y0841D03*
X08466Y0746D03*
X07661Y06599D03*
X08892Y06099D03*
X09545Y06945D03*
X09268Y06809D03*
X09265Y0861D03*
X1066D03*
X09959Y06675D03*
X09951Y07728D03*
X08601Y05938D03*
X1227257Y0823D03*
X09797Y08239D03*
X09794Y06695D03*
X08464Y07984D03*
X08676Y07315D03*
X08597Y06095D03*
X07252Y07486D03*
X09709Y06717D03*
X0954Y06417D03*
X08872Y0757D03*
X07709Y06501D03*
X07712Y06894D03*
X08875Y07903D03*
X09987Y06715D03*
X08404Y08299D03*
X10105Y08139D03*
X12639Y08345D03*
X0832Y08365D03*
X08622Y0788D03*
X08879Y09225D03*
X09361Y07892D03*
X084Y07583D03*
X07661Y06698D03*
X08833Y06099D03*
X08753Y07906D03*
X08249Y08745D03*
X08406Y07796D03*
X08572Y07312D03*
X08499Y06094D03*
X0774Y09114D03*
X08561Y09287D03*
X0745Y08151D03*
X07431Y08561D03*
X07576Y09129D03*
X07894Y09022D03*
X08235Y09021D03*
X08281Y09221D03*
X09871Y08113D03*
X09482Y08107D03*
X08812Y07605D03*
X09614Y07591D03*
X09613Y0849D03*
X09482Y08301D03*
X0953302Y0832298D03*
X09335Y08D03*
X09735Y08346D03*
X09644Y08297D03*
X09385Y08451D03*
X09427Y08461D03*
X09349Y08452D03*
X09708Y08076D03*
X08425Y0855D03*
X0857Y0849D03*
X07884Y06697D03*
X09215Y0666528D03*
X0879Y0862D03*
X0958Y06715D03*
X0901Y054D03*
X11724Y0856D03*
X11667Y0855D03*
X08405Y05941D03*
X09594Y05686D03*
X08469Y05941D03*
X08715Y06097D03*
X12619Y06376D03*
X12539Y06535D03*
X12593Y06616D03*
Y06676D03*
Y06726D03*
X12592Y06781D03*
X12676Y06832D03*
X1269Y06885D03*
X13042Y06961D03*
X1294Y07099D03*
X12598Y0718D03*
X12386Y07115D03*
X12039Y07175D03*
X11995Y07438D03*
X12265Y07395D03*
X12389Y07457D03*
X12388Y07505D03*
X12387Y0756D03*
X12388Y07614D03*
X12389Y07661D03*
X123622Y0791339D03*
X10901Y09207D03*
X10378Y0921D03*
X09768Y09027D03*
X10076Y08896D03*
X10185Y08888D03*
X10422Y08139D03*
X09321Y08305D03*
X0909Y07916D03*
X09023Y07972D03*
X09009Y07901D03*
X08851Y08791D03*
X08715Y08733D03*
X09522Y08664D03*
X0926Y08792D03*
X07233Y06476D03*
X07247Y05946D03*
X06645Y05794D03*
X06646Y06032D03*
X06645Y06318D03*
X06644Y06555D03*
X06645Y06843D03*
Y07077D03*
Y07369D03*
X0664412Y0759783D03*
X08717Y07297D03*
X08622Y05978D03*
X08933Y0729D03*
X08734Y05827D03*
X08783Y0579D03*
X08656Y07295D03*
X08658Y05985D03*
X09885Y0657D03*
X084Y07318D03*
X07556Y06323D03*
X08582Y05817D03*
X08794Y07311D03*
X08976Y07291D03*
X08466Y07295D03*
X087657Y0582263D03*
X08822Y05792D03*
X08727Y05947D03*
X09855Y06515D03*
X09395Y0636726D03*
X09289Y06975D03*
X07875Y07075D03*
X09383Y06875D03*
X08692Y05985D03*
X0873525Y0599177D03*
X08911Y07432D03*
X08949Y07625D03*
X08636Y07278D03*
X084Y07287D03*
X088Y05978D03*
X0937Y0639D03*
X08441Y07286D03*
X09243Y06665D03*
X0954Y06445D03*
X08939Y0746D03*
X0761Y07125D03*
X08588Y05979D03*
X0937Y0634D03*
X0771Y0654D03*
X08616Y05817D03*
X09825Y06485D03*
X08885Y07435D03*
X07745Y0713D03*
X0882941Y0599141D03*
X07782Y06301D03*
X0939744Y0641526D03*
X08832Y07267D03*
X0957Y07947D03*
X09221Y08239D03*
X09243Y08297D03*
X08197Y06302D03*
X08196Y08204D03*
X08495Y08086D03*
X08493Y0632D03*
X0841Y08198D03*
X08581Y08292D03*
X08582Y08204D03*
X08516Y07467D03*
X09333Y07267D03*
X09489Y07345D03*
X0841935Y07625D03*
X06995Y0591D03*
X08437Y06441D03*
X06999Y06434D03*
X084Y06971D03*
X07Y0696D03*
X07011Y07485D03*
X08634Y0662D03*
X08657Y06644D03*
X08345Y05434D03*
X08369D03*
X0876532Y0598081D03*
X0897Y05398D03*
X08695Y054D03*
X08655Y05401D03*
X0846Y05402D03*
X08502Y05401D03*
X0957Y0759D03*
X07875Y08605D03*
X07745Y08665D03*
X09415Y0864D03*
X0754Y08625D03*
X0923Y086D03*
X07565D03*
X0953Y0881D03*
X0921D03*
X0871257Y0879001D03*
X0813Y08615D03*
X08075Y089D03*
X08074Y064156D03*
X0805Y0639D03*
Y08875D03*
X0802Y0884D03*
X08019Y063656D03*
X07285Y0926D03*
X07995Y0882D03*
Y0634D03*
X08225Y0851D03*
X0952Y08485D03*
X11265Y08515D03*
X12275Y07505D03*
X0867Y08665D03*
X08765Y0857D03*
X09562Y07037D03*
X0898354Y08755D03*
X0969D03*
X09005Y08835D03*
X0969Y0884D03*
X10245Y0878D03*
X08885Y06565D03*
X0891Y0654D03*
X09985Y06555D03*
X08265Y0651D03*
X10025Y0655D03*
X0871Y06595D03*
X1017Y06605D03*
X1014146Y0662756D03*
X10125Y06655D03*
X09715Y06679D03*
X12835Y06665D03*
X12415Y07185D03*
X1229957Y08203D03*
X1233Y08155D03*
X1074487Y0911987D03*
X0777Y0916D03*
X09495Y0909D03*
X09845Y08155D03*
X0982Y0818D03*
X0979Y08205D03*
X1243Y08195D03*
X1234491Y0833508D03*
X12435Y08295D03*
X09293Y08348D03*
X124Y08375D03*
X1243773Y084D03*
X1247Y0843D03*
X125Y0846D03*
X0946D03*
X0784Y08705D03*
X12285D03*
M02*